# T6G (Grand Teton) — schematic netlist excerpt (pin names and nets, part order shuffled) for the footprints in the layout excerpt that follows; sources: Cadence DE-HDL packaged netlist, KiCad conversion of 04192023_DAF0TMB3IC0_F0TG_MB_C_brd_V02_OCP.brd

PC2196  Q_CAP  0.22UF 16V 10% X7R  pkg 0402  page 147 : A = P12V_E1S_TIMER_0 ; B = GND
PR3984  Q_RES  120K 1% CHIP  pkg 0402LF  page 264 : A = AGND_HSC ; B = HSC_MODE_4

(kicad_pcb
	(version 20260206)
	(generator "pcbnew")
	(generator_version "10.0")
	(general
		(thickness 1.6)
		(legacy_teardrops no)
	)
	(paper "A4")
	(title_block
		(title "04192023_DAF0TMB3IC0_F0TG_MB_C_brd_V02_OCP.brd")
		(comment 1 "Grand Teton / footprints 851-852 of 8354")
	)
	(layers
		(0 "F.Cu" signal "TOP")
		(4 "In1.Cu" signal "GND")
		(6 "In2.Cu" signal "IN1")
		(8 "In3.Cu" signal "GND1")
		(10 "In4.Cu" signal "IN2")
		(12 "In5.Cu" signal "GND2")
		(14 "In6.Cu" signal "IN3")
		(16 "In7.Cu" signal "GND3")
		(18 "In8.Cu" signal "VCC")
		(20 "In9.Cu" signal "VCC1")
		(22 "In10.Cu" signal "GND4")
		(24 "In11.Cu" signal "IN4")
		(26 "In12.Cu" signal "GND5")
		(28 "In13.Cu" signal "IN5")
		(30 "In14.Cu" signal "GND6")
		(32 "In15.Cu" signal "IN6")
		(34 "In16.Cu" signal "GND7")
		(2 "B.Cu" signal "BOTTOM")
		(9 "F.Adhes" user "F.Adhesive")
		(11 "B.Adhes" user "B.Adhesive")
		(13 "F.Paste" user "Package Geometry/Pastemask Top")
		(15 "B.Paste" user "Package Geometry/Pastemask Bottom")
		(5 "F.SilkS" user "Ref Des/Silkscreen Top")
		(7 "B.SilkS" user "Ref Des/Silkscreen Bottom")
		(1 "F.Mask" user "Board Geometry/Soldermask Top")
		(3 "B.Mask" user "Board Geometry/Soldermask Bottom")
		(17 "Dwgs.User" user "User.Drawings")
		(19 "Cmts.User" user "User.Comments")
		(21 "Eco1.User" user "User.Eco1")
		(23 "Eco2.User" user "User.Eco2")
		(25 "Edge.Cuts" user "Board Geometry/Outline")
		(27 "Margin" user)
		(31 "F.CrtYd" user "Package Geometry/Place Bound Top")
		(29 "B.CrtYd" user "Package Geometry/Place Bound Bottom")
		(35 "F.Fab" user "Ref Des/Assembly Top")
		(33 "B.Fab" user "Ref Des/Assembly Bottom")
	)
	(footprint ""
		(layer "F.Cu")
		(at 236.7661 -403.919182 180)
		(property "Reference" "PR3984"
			(at 0 0 180)
			(layer "F.SilkS")
			(hide yes)
			(effects
				(font
					(size 1.27 1.27)
				)
			)
		)
		(property "Value" ""
			(at 0 0 180)
			(layer "F.Fab")
			(effects
				(font
					(size 1.27 1.27)
				)
			)
		)
		(duplicate_pad_numbers_are_jumpers no)
		(fp_line
			(start 0.7874 0.4064)
			(end -0.7874 0.4064)
			(stroke
				(width 0.1524)
				(type default)
			)
			(layer "F.SilkS")
		)
		(fp_line
			(start 0.7874 -0.4064)
			(end 0.7874 0.4064)
			(stroke
				(width 0.1524)
				(type default)
			)
			(layer "F.SilkS")
		)
		(fp_line
			(start -0.7874 0.4064)
			(end -0.7874 -0.4064)
			(stroke
				(width 0.1524)
				(type default)
			)
			(layer "F.SilkS")
		)
		(fp_line
			(start -0.7874 -0.4064)
			(end 0.7874 -0.4064)
			(stroke
				(width 0.1524)
				(type default)
			)
			(layer "F.SilkS")
		)
		(fp_line
			(start 0.67945 0.3048)
			(end 0.120396 0.3048)
			(stroke
				(width 0.1)
				(type default)
			)
			(layer "F.Fab")
		)
		(fp_line
			(start 0.67945 -0.3048)
			(end 0.67945 0.3048)
			(stroke
				(width 0.1)
				(type default)
			)
			(layer "F.Fab")
		)
		(fp_line
			(start 0.12065 -0.2794)
			(end 0.12065 -0.3048)
			(stroke
				(width 0.1)
				(type default)
			)
			(layer "F.Fab")
		)
		(fp_line
			(start 0.12065 -0.3048)
			(end 0.67945 -0.3048)
			(stroke
				(width 0.1)
				(type default)
			)
			(layer "F.Fab")
		)
		(fp_line
			(start 0.120396 0.3048)
			(end 0.120396 0.2794)
			(stroke
				(width 0.1)
				(type default)
			)
			(layer "F.Fab")
		)
		(fp_line
			(start 0.120396 0.2794)
			(end -0.12065 0.2794)
			(stroke
				(width 0.1)
				(type default)
			)
			(layer "F.Fab")
		)
		(fp_line
			(start -0.12065 0.3048)
			(end -0.67945 0.3048)
			(stroke
				(width 0.1)
				(type default)
			)
			(layer "F.Fab")
		)
		(fp_line
			(start -0.12065 0.2794)
			(end -0.12065 0.3048)
			(stroke
				(width 0.1)
				(type default)
			)
			(layer "F.Fab")
		)
		(fp_line
			(start -0.12065 -0.2794)
			(end 0.12065 -0.2794)
			(stroke
				(width 0.1)
				(type default)
			)
			(layer "F.Fab")
		)
		(fp_line
			(start -0.12065 -0.305054)
			(end -0.12065 -0.2794)
			(stroke
				(width 0.1)
				(type default)
			)
			(layer "F.Fab")
		)
		(fp_line
			(start -0.67945 0.3048)
			(end -0.67945 -0.305054)
			(stroke
				(width 0.1)
				(type default)
			)
			(layer "F.Fab")
		)
		(fp_line
			(start -0.67945 -0.305054)
			(end -0.12065 -0.305054)
			(stroke
				(width 0.1)
				(type default)
			)
			(layer "F.Fab")
		)
		(pad "1" smd circle
			(at -0.40005 0 180)
			(size 0 0)
			(layers "F.Cu" "F.Mask" "F.Paste")
			(net "AGND_HSC")
		)
		(pad "2" smd circle
			(at 0.40005 0 180)
			(size 0 0)
			(layers "F.Cu" "F.Mask" "F.Paste")
			(net "HSC_MODE_4")
		)
	)
	(footprint ""
		(layer "F.Cu")
		(at 257.86588 -50.545746)
		(property "Reference" "PC2196"
			(at 0 0 0)
			(layer "F.SilkS")
			(hide yes)
			(effects
				(font
					(size 1.27 1.27)
				)
			)
		)
		(property "Value" ""
			(at 0 0 0)
			(layer "F.Fab")
			(effects
				(font
					(size 1.27 1.27)
				)
			)
		)
		(duplicate_pad_numbers_are_jumpers no)
		(fp_line
			(start -0.7874 -0.4064)
			(end 0.7874 -0.4064)
			(stroke
				(width 0.1524)
				(type default)
			)
			(layer "F.SilkS")
		)
		(fp_line
			(start -0.7874 0.4064)
			(end -0.7874 -0.4064)
			(stroke
				(width 0.1524)
				(type default)
			)
			(layer "F.SilkS")
		)
		(fp_line
			(start 0.7874 -0.4064)
			(end 0.7874 0.4064)
			(stroke
				(width 0.1524)
				(type default)
			)
			(layer "F.SilkS")
		)
		(fp_line
			(start 0.7874 0.4064)
			(end -0.7874 0.4064)
			(stroke
				(width 0.1524)
				(type default)
			)
			(layer "F.SilkS")
		)
		(fp_line
			(start -0.67945 -0.305054)
			(end -0.12065 -0.305054)
			(stroke
				(width 0.1)
				(type default)
			)
			(layer "F.Fab")
		)
		(fp_line
			(start -0.67945 0.3048)
			(end -0.67945 -0.305054)
			(stroke
				(width 0.1)
				(type default)
			)
			(layer "F.Fab")
		)
		(fp_line
			(start -0.12065 -0.305054)
			(end -0.12065 -0.2794)
			(stroke
				(width 0.1)
				(type default)
			)
			(layer "F.Fab")
		)
		(fp_line
			(start -0.12065 -0.2794)
			(end 0.12065 -0.2794)
			(stroke
				(width 0.1)
				(type default)
			)
			(layer "F.Fab")
		)
		(fp_line
			(start -0.12065 0.2794)
			(end -0.12065 0.3048)
			(stroke
				(width 0.1)
				(type default)
			)
			(layer "F.Fab")
		)
		(fp_line
			(start -0.12065 0.3048)
			(end -0.67945 0.3048)
			(stroke
				(width 0.1)
				(type default)
			)
			(layer "F.Fab")
		)
		(fp_line
			(start 0.120396 0.2794)
			(end -0.12065 0.2794)
			(stroke
				(width 0.1)
				(type default)
			)
			(layer "F.Fab")
		)
		(fp_line
			(start 0.120396 0.3048)
			(end 0.120396 0.2794)
			(stroke
				(width 0.1)
				(type default)
			)
			(layer "F.Fab")
		)
		(fp_line
			(start 0.12065 -0.3048)
			(end 0.67945 -0.3048)
			(stroke
				(width 0.1)
				(type default)
			)
			(layer "F.Fab")
		)
		(fp_line
			(start 0.12065 -0.2794)
			(end 0.12065 -0.3048)
			(stroke
				(width 0.1)
				(type default)
			)
			(layer "F.Fab")
		)
		(fp_line
			(start 0.67945 -0.3048)
			(end 0.67945 0.3048)
			(stroke
				(width 0.1)
				(type default)
			)
			(layer "F.Fab")
		)
		(fp_line
			(start 0.67945 0.3048)
			(end 0.120396 0.3048)
			(stroke
				(width 0.1)
				(type default)
			)
			(layer "F.Fab")
		)
		(pad "1" smd circle
			(at -0.40005 0)
			(size 0 0)
			(layers "F.Cu" "F.Mask" "F.Paste")
			(net "P12V_E1S_TIMER_0")
		)
		(pad "2" smd circle
			(at 0.40005 0)
			(size 0 0)
			(layers "F.Cu" "F.Mask" "F.Paste")
			(net "GND")
		)
	)
)
